(kicad_pcb
	(version 20260206)
	(generator "pcbnew")
	(generator_version "10.0")
	(general
		(thickness 1.6)
		(legacy_teardrops no)
	)
	(paper "A4")
	(title_block
		(title "04192023_DAF0TMB3IC0_F0TG_MB_C_brd_V02_OCP.brd")
		(comment 1 "Grand Teton / footprints 2239-2244 of 8354")
	)
	(layers
		(0 "F.Cu" signal "TOP")
		(4 "In1.Cu" signal "GND")
		(6 "In2.Cu" signal "IN1")
		(8 "In3.Cu" signal "GND1")
		(10 "In4.Cu" signal "IN2")
		(12 "In5.Cu" signal "GND2")
		(14 "In6.Cu" signal "IN3")
		(16 "In7.Cu" signal "GND3")
		(18 "In8.Cu" signal "VCC")
		(20 "In9.Cu" signal "VCC1")
		(22 "In10.Cu" signal "GND4")
		(24 "In11.Cu" signal "IN4")
		(26 "In12.Cu" signal "GND5")
		(28 "In13.Cu" signal "IN5")
		(30 "In14.Cu" signal "GND6")
		(32 "In15.Cu" signal "IN6")
		(34 "In16.Cu" signal "GND7")
		(2 "B.Cu" signal "BOTTOM")
		(9 "F.Adhes" user "F.Adhesive")
		(11 "B.Adhes" user "B.Adhesive")
		(13 "F.Paste" user "Package Geometry/Pastemask Top")
		(15 "B.Paste" user "Package Geometry/Pastemask Bottom")
		(5 "F.SilkS" user "Ref Des/Silkscreen Top")
		(7 "B.SilkS" user "Ref Des/Silkscreen Bottom")
		(1 "F.Mask" user "Board Geometry/Soldermask Top")
		(3 "B.Mask" user "Board Geometry/Soldermask Bottom")
		(17 "Dwgs.User" user "User.Drawings")
		(19 "Cmts.User" user "User.Comments")
		(21 "Eco1.User" user "User.Eco1")
		(23 "Eco2.User" user "User.Eco2")
		(25 "Edge.Cuts" user "Board Geometry/Outline")
		(27 "Margin" user)
		(31 "F.CrtYd" user "Package Geometry/Place Bound Top")
		(29 "B.CrtYd" user "Package Geometry/Place Bound Bottom")
		(35 "F.Fab" user "Ref Des/Assembly Top")
		(33 "B.Fab" user "Ref Des/Assembly Bottom")
	)
	(footprint ""
		(layer "F.Cu")
		(at 37.338 -366.776 -90)
		(property "Reference" "PR603"
			(at 0 0 270)
			(layer "F.SilkS")
			(hide yes)
			(effects
				(font
					(size 1.27 1.27)
				)
			)
		)
		(property "Value" ""
			(at 0 0 270)
			(layer "F.Fab")
			(effects
				(font
					(size 1.27 1.27)
				)
			)
		)
		(duplicate_pad_numbers_are_jumpers no)
		(fp_line
			(start -0.7874 0.4064)
			(end -0.7874 -0.4064)
			(stroke
				(width 0.1524)
				(type default)
			)
			(layer "F.SilkS")
		)
		(fp_line
			(start 0.7874 0.4064)
			(end -0.7874 0.4064)
			(stroke
				(width 0.1524)
				(type default)
			)
			(layer "F.SilkS")
		)
		(fp_line
			(start -0.7874 -0.4064)
			(end 0.7874 -0.4064)
			(stroke
				(width 0.1524)
				(type default)
			)
			(layer "F.SilkS")
		)
		(fp_line
			(start 0.7874 -0.4064)
			(end 0.7874 0.4064)
			(stroke
				(width 0.1524)
				(type default)
			)
			(layer "F.SilkS")
		)
		(fp_line
			(start -0.67945 0.3048)
			(end -0.67945 -0.305054)
			(stroke
				(width 0.1)
				(type default)
			)
			(layer "F.Fab")
		)
		(fp_line
			(start -0.12065 0.3048)
			(end -0.67945 0.3048)
			(stroke
				(width 0.1)
				(type default)
			)
			(layer "F.Fab")
		)
		(fp_line
			(start 0.120396 0.3048)
			(end 0.120396 0.2794)
			(stroke
				(width 0.1)
				(type default)
			)
			(layer "F.Fab")
		)
		(fp_line
			(start 0.67945 0.3048)
			(end 0.120396 0.3048)
			(stroke
				(width 0.1)
				(type default)
			)
			(layer "F.Fab")
		)
		(fp_line
			(start -0.12065 0.2794)
			(end -0.12065 0.3048)
			(stroke
				(width 0.1)
				(type default)
			)
			(layer "F.Fab")
		)
		(fp_line
			(start 0.120396 0.2794)
			(end -0.12065 0.2794)
			(stroke
				(width 0.1)
				(type default)
			)
			(layer "F.Fab")
		)
		(fp_line
			(start -0.12065 -0.2794)
			(end 0.12065 -0.2794)
			(stroke
				(width 0.1)
				(type default)
			)
			(layer "F.Fab")
		)
		(fp_line
			(start 0.12065 -0.2794)
			(end 0.12065 -0.3048)
			(stroke
				(width 0.1)
				(type default)
			)
			(layer "F.Fab")
		)
		(fp_line
			(start 0.12065 -0.3048)
			(end 0.67945 -0.3048)
			(stroke
				(width 0.1)
				(type default)
			)
			(layer "F.Fab")
		)
		(fp_line
			(start 0.67945 -0.3048)
			(end 0.67945 0.3048)
			(stroke
				(width 0.1)
				(type default)
			)
			(layer "F.Fab")
		)
		(fp_line
			(start -0.67945 -0.305054)
			(end -0.12065 -0.305054)
			(stroke
				(width 0.1)
				(type default)
			)
			(layer "F.Fab")
		)
		(fp_line
			(start -0.12065 -0.305054)
			(end -0.12065 -0.2794)
			(stroke
				(width 0.1)
				(type default)
			)
			(layer "F.Fab")
		)
		(pad "1" smd circle
			(at -0.40005 0 270)
			(size 0 0)
			(layers "F.Cu" "F.Mask" "F.Paste")
			(net "PVDDCR_CPU1_P1_VINSEN")
		)
		(pad "2" smd circle
			(at 0.40005 0 270)
			(size 0 0)
			(layers "F.Cu" "F.Mask" "F.Paste")
			(net "GND")
		)
	)
	(footprint ""
		(layer "F.Cu")
		(at 119.379492 -174.927768)
		(property "Reference" "PC141"
			(at 0 0 0)
			(layer "F.SilkS")
			(hide yes)
			(effects
				(font
					(size 1.27 1.27)
				)
			)
		)
		(property "Value" ""
			(at 0 0 0)
			(layer "F.Fab")
			(effects
				(font
					(size 1.27 1.27)
				)
			)
		)
		(duplicate_pad_numbers_are_jumpers no)
		(fp_line
			(start -0.7874 -0.4064)
			(end 0.7874 -0.4064)
			(stroke
				(width 0.1524)
				(type default)
			)
			(layer "F.SilkS")
		)
		(fp_line
			(start -0.7874 0.4064)
			(end -0.7874 -0.4064)
			(stroke
				(width 0.1524)
				(type default)
			)
			(layer "F.SilkS")
		)
		(fp_line
			(start 0.7874 -0.4064)
			(end 0.7874 0.4064)
			(stroke
				(width 0.1524)
				(type default)
			)
			(layer "F.SilkS")
		)
		(fp_line
			(start 0.7874 0.4064)
			(end -0.7874 0.4064)
			(stroke
				(width 0.1524)
				(type default)
			)
			(layer "F.SilkS")
		)
		(fp_line
			(start -0.67945 -0.305054)
			(end -0.12065 -0.305054)
			(stroke
				(width 0.1)
				(type default)
			)
			(layer "F.Fab")
		)
		(fp_line
			(start -0.67945 0.3048)
			(end -0.67945 -0.305054)
			(stroke
				(width 0.1)
				(type default)
			)
			(layer "F.Fab")
		)
		(fp_line
			(start -0.12065 -0.305054)
			(end -0.12065 -0.2794)
			(stroke
				(width 0.1)
				(type default)
			)
			(layer "F.Fab")
		)
		(fp_line
			(start -0.12065 -0.2794)
			(end 0.12065 -0.2794)
			(stroke
				(width 0.1)
				(type default)
			)
			(layer "F.Fab")
		)
		(fp_line
			(start -0.12065 0.2794)
			(end -0.12065 0.3048)
			(stroke
				(width 0.1)
				(type default)
			)
			(layer "F.Fab")
		)
		(fp_line
			(start -0.12065 0.3048)
			(end -0.67945 0.3048)
			(stroke
				(width 0.1)
				(type default)
			)
			(layer "F.Fab")
		)
		(fp_line
			(start 0.120396 0.2794)
			(end -0.12065 0.2794)
			(stroke
				(width 0.1)
				(type default)
			)
			(layer "F.Fab")
		)
		(fp_line
			(start 0.120396 0.3048)
			(end 0.120396 0.2794)
			(stroke
				(width 0.1)
				(type default)
			)
			(layer "F.Fab")
		)
		(fp_line
			(start 0.12065 -0.3048)
			(end 0.67945 -0.3048)
			(stroke
				(width 0.1)
				(type default)
			)
			(layer "F.Fab")
		)
		(fp_line
			(start 0.12065 -0.2794)
			(end 0.12065 -0.3048)
			(stroke
				(width 0.1)
				(type default)
			)
			(layer "F.Fab")
		)
		(fp_line
			(start 0.67945 -0.3048)
			(end 0.67945 0.3048)
			(stroke
				(width 0.1)
				(type default)
			)
			(layer "F.Fab")
		)
		(fp_line
			(start 0.67945 0.3048)
			(end 0.120396 0.3048)
			(stroke
				(width 0.1)
				(type default)
			)
			(layer "F.Fab")
		)
		(pad "1" smd circle
			(at -0.40005 0)
			(size 0 0)
			(layers "F.Cu" "F.Mask" "F.Paste")
			(net "SW_PVDDCR_SOC_P1_SW1")
		)
		(pad "2" smd circle
			(at 0.40005 0)
			(size 0 0)
			(layers "F.Cu" "F.Mask" "F.Paste")
			(net "SW_PVDDCR_SOC_P1_SW1_RC")
		)
	)
	(footprint ""
		(layer "F.Cu")
		(at 453.054212 -23.603458)
		(property "Reference" "PC4056"
			(at 0 0 0)
			(layer "F.SilkS")
			(hide yes)
			(effects
				(font
					(size 1.27 1.27)
				)
			)
		)
		(property "Value" ""
			(at 0 0 0)
			(layer "F.Fab")
			(effects
				(font
					(size 1.27 1.27)
				)
			)
		)
		(duplicate_pad_numbers_are_jumpers no)
		(fp_line
			(start -0.7874 -0.4064)
			(end 0.7874 -0.4064)
			(stroke
				(width 0.1524)
				(type default)
			)
			(layer "F.SilkS")
		)
		(fp_line
			(start -0.7874 0.4064)
			(end -0.7874 -0.4064)
			(stroke
				(width 0.1524)
				(type default)
			)
			(layer "F.SilkS")
		)
		(fp_line
			(start 0.7874 -0.4064)
			(end 0.7874 0.4064)
			(stroke
				(width 0.1524)
				(type default)
			)
			(layer "F.SilkS")
		)
		(fp_line
			(start 0.7874 0.4064)
			(end -0.7874 0.4064)
			(stroke
				(width 0.1524)
				(type default)
			)
			(layer "F.SilkS")
		)
		(fp_line
			(start -0.67945 -0.305054)
			(end -0.12065 -0.305054)
			(stroke
				(width 0.1)
				(type default)
			)
			(layer "F.Fab")
		)
		(fp_line
			(start -0.67945 0.3048)
			(end -0.67945 -0.305054)
			(stroke
				(width 0.1)
				(type default)
			)
			(layer "F.Fab")
		)
		(fp_line
			(start -0.12065 -0.305054)
			(end -0.12065 -0.2794)
			(stroke
				(width 0.1)
				(type default)
			)
			(layer "F.Fab")
		)
		(fp_line
			(start -0.12065 -0.2794)
			(end 0.12065 -0.2794)
			(stroke
				(width 0.1)
				(type default)
			)
			(layer "F.Fab")
		)
		(fp_line
			(start -0.12065 0.2794)
			(end -0.12065 0.3048)
			(stroke
				(width 0.1)
				(type default)
			)
			(layer "F.Fab")
		)
		(fp_line
			(start -0.12065 0.3048)
			(end -0.67945 0.3048)
			(stroke
				(width 0.1)
				(type default)
			)
			(layer "F.Fab")
		)
		(fp_line
			(start 0.120396 0.2794)
			(end -0.12065 0.2794)
			(stroke
				(width 0.1)
				(type default)
			)
			(layer "F.Fab")
		)
		(fp_line
			(start 0.120396 0.3048)
			(end 0.120396 0.2794)
			(stroke
				(width 0.1)
				(type default)
			)
			(layer "F.Fab")
		)
		(fp_line
			(start 0.12065 -0.3048)
			(end 0.67945 -0.3048)
			(stroke
				(width 0.1)
				(type default)
			)
			(layer "F.Fab")
		)
		(fp_line
			(start 0.12065 -0.2794)
			(end 0.12065 -0.3048)
			(stroke
				(width 0.1)
				(type default)
			)
			(layer "F.Fab")
		)
		(fp_line
			(start 0.67945 -0.3048)
			(end 0.67945 0.3048)
			(stroke
				(width 0.1)
				(type default)
			)
			(layer "F.Fab")
		)
		(fp_line
			(start 0.67945 0.3048)
			(end 0.120396 0.3048)
			(stroke
				(width 0.1)
				(type default)
			)
			(layer "F.Fab")
		)
		(pad "1" smd circle
			(at -0.40005 0)
			(size 0 0)
			(layers "F.Cu" "F.Mask" "F.Paste")
			(net "P12V_OCP_GATE_1")
		)
		(pad "2" smd circle
			(at 0.40005 0)
			(size 0 0)
			(layers "F.Cu" "F.Mask" "F.Paste")
			(net "GND")
		)
	)
	(footprint ""
		(layer "F.Cu")
		(at 294.421052 -117.269514)
		(property "Reference" "R2565"
			(at 0 0 0)
			(layer "F.SilkS")
			(hide yes)
			(effects
				(font
					(size 1.27 1.27)
				)
			)
		)
		(property "Value" ""
			(at 0 0 0)
			(layer "F.Fab")
			(effects
				(font
					(size 1.27 1.27)
				)
			)
		)
		(duplicate_pad_numbers_are_jumpers no)
		(fp_line
			(start -0.7874 -0.4064)
			(end 0.7874 -0.4064)
			(stroke
				(width 0.1524)
				(type default)
			)
			(layer "F.SilkS")
		)
		(fp_line
			(start -0.7874 0.4064)
			(end -0.7874 -0.4064)
			(stroke
				(width 0.1524)
				(type default)
			)
			(layer "F.SilkS")
		)
		(fp_line
			(start 0.7874 -0.4064)
			(end 0.7874 0.4064)
			(stroke
				(width 0.1524)
				(type default)
			)
			(layer "F.SilkS")
		)
		(fp_line
			(start 0.7874 0.4064)
			(end -0.7874 0.4064)
			(stroke
				(width 0.1524)
				(type default)
			)
			(layer "F.SilkS")
		)
		(fp_line
			(start -0.67945 -0.305054)
			(end -0.12065 -0.305054)
			(stroke
				(width 0.1)
				(type default)
			)
			(layer "F.Fab")
		)
		(fp_line
			(start -0.67945 0.3048)
			(end -0.67945 -0.305054)
			(stroke
				(width 0.1)
				(type default)
			)
			(layer "F.Fab")
		)
		(fp_line
			(start -0.12065 -0.305054)
			(end -0.12065 -0.2794)
			(stroke
				(width 0.1)
				(type default)
			)
			(layer "F.Fab")
		)
		(fp_line
			(start -0.12065 -0.2794)
			(end 0.12065 -0.2794)
			(stroke
				(width 0.1)
				(type default)
			)
			(layer "F.Fab")
		)
		(fp_line
			(start -0.12065 0.2794)
			(end -0.12065 0.3048)
			(stroke
				(width 0.1)
				(type default)
			)
			(layer "F.Fab")
		)
		(fp_line
			(start -0.12065 0.3048)
			(end -0.67945 0.3048)
			(stroke
				(width 0.1)
				(type default)
			)
			(layer "F.Fab")
		)
		(fp_line
			(start 0.120396 0.2794)
			(end -0.12065 0.2794)
			(stroke
				(width 0.1)
				(type default)
			)
			(layer "F.Fab")
		)
		(fp_line
			(start 0.120396 0.3048)
			(end 0.120396 0.2794)
			(stroke
				(width 0.1)
				(type default)
			)
			(layer "F.Fab")
		)
		(fp_line
			(start 0.12065 -0.3048)
			(end 0.67945 -0.3048)
			(stroke
				(width 0.1)
				(type default)
			)
			(layer "F.Fab")
		)
		(fp_line
			(start 0.12065 -0.2794)
			(end 0.12065 -0.3048)
			(stroke
				(width 0.1)
				(type default)
			)
			(layer "F.Fab")
		)
		(fp_line
			(start 0.67945 -0.3048)
			(end 0.67945 0.3048)
			(stroke
				(width 0.1)
				(type default)
			)
			(layer "F.Fab")
		)
		(fp_line
			(start 0.67945 0.3048)
			(end 0.120396 0.3048)
			(stroke
				(width 0.1)
				(type default)
			)
			(layer "F.Fab")
		)
		(pad "1" smd circle
			(at -0.40005 0)
			(size 0 0)
			(layers "F.Cu" "F.Mask" "F.Paste")
			(net "SMB_FRU_3V3AUX_SCL_R")
		)
		(pad "2" smd circle
			(at 0.40005 0)
			(size 0 0)
			(layers "F.Cu" "F.Mask" "F.Paste")
			(net "SMB_FRU_3V3AUX_SCL")
		)
	)
	(footprint ""
		(layer "F.Cu")
		(at 218.31681 -135.78459)
		(property "Reference" "Q64"
			(at -1.4224 -2.327148 0)
			(unlocked yes)
			(layer "F.SilkS")
			(effects
				(font
					(size 0.7874 0.5842)
					(thickness 0.1524)
				)
			)
		)
		(property "Value" ""
			(at 0 0 0)
			(layer "F.Fab")
			(effects
				(font
					(size 1.27 1.27)
				)
			)
		)
		(duplicate_pad_numbers_are_jumpers no)
		(fp_line
			(start -1.949958 -1.610106)
			(end 1.949958 -1.610106)
			(stroke
				(width 0.1524)
				(type default)
			)
			(layer "F.SilkS")
		)
		(fp_line
			(start -1.949958 1.610106)
			(end -1.949958 -1.610106)
			(stroke
				(width 0.1524)
				(type default)
			)
			(layer "F.SilkS")
		)
		(fp_line
			(start 1.949958 -1.560068)
			(end 1.949958 1.610106)
			(stroke
				(width 0.1524)
				(type default)
			)
			(layer "F.SilkS")
		)
		(fp_line
			(start 1.949958 1.610106)
			(end -1.949958 1.610106)
			(stroke
				(width 0.1524)
				(type default)
			)
			(layer "F.SilkS")
		)
		(fp_line
			(start -0.750062 -1.560068)
			(end 0.750062 -1.560068)
			(stroke
				(width 0.1)
				(type default)
			)
			(layer "F.Fab")
		)
		(fp_line
			(start -0.750062 1.560068)
			(end -0.750062 -1.560068)
			(stroke
				(width 0.1)
				(type default)
			)
			(layer "F.Fab")
		)
		(fp_line
			(start 0.750062 -1.560068)
			(end 0.750062 1.560068)
			(stroke
				(width 0.1)
				(type default)
			)
			(layer "F.Fab")
		)
		(fp_line
			(start 0.750062 1.560068)
			(end -0.750062 1.560068)
			(stroke
				(width 0.1)
				(type default)
			)
			(layer "F.Fab")
		)
		(pad "D" smd rect
			(at 1.100074 0 270)
			(size 1.016 1.4224)
			(layers "F.Cu" "F.Mask" "F.Paste")
			(net "FM_PLD_CPU1_PRSNT_HDT_N")
		)
		(pad "G" smd rect
			(at -1.100074 -0.94996 270)
			(size 1.016 1.4224)
			(layers "F.Cu" "F.Mask" "F.Paste")
			(net "CPU1_HDT_BYPASS_SEL")
		)
		(pad "S" smd rect
			(at -1.100074 0.94996 270)
			(size 1.016 1.4224)
			(layers "F.Cu" "F.Mask" "F.Paste")
			(net "GND")
		)
	)
	(footprint ""
		(layer "F.Cu")
		(at 365.835692 -256.505202 180)
		(property "Reference" "C2551"
			(at 0 0 180)
			(layer "F.SilkS")
			(hide yes)
			(effects
				(font
					(size 1.27 1.27)
				)
			)
		)
		(property "Value" ""
			(at 0 0 180)
			(layer "F.Fab")
			(effects
				(font
					(size 1.27 1.27)
				)
			)
		)
		(duplicate_pad_numbers_are_jumpers no)
		(fp_line
			(start 0.7874 0.4064)
			(end -0.7874 0.4064)
			(stroke
				(width 0.1524)
				(type default)
			)
			(layer "F.SilkS")
		)
		(fp_line
			(start 0.7874 -0.4064)
			(end 0.7874 0.4064)
			(stroke
				(width 0.1524)
				(type default)
			)
			(layer "F.SilkS")
		)
		(fp_line
			(start -0.7874 0.4064)
			(end -0.7874 -0.4064)
			(stroke
				(width 0.1524)
				(type default)
			)
			(layer "F.SilkS")
		)
		(fp_line
			(start -0.7874 -0.4064)
			(end 0.7874 -0.4064)
			(stroke
				(width 0.1524)
				(type default)
			)
			(layer "F.SilkS")
		)
		(fp_line
			(start 0.67945 0.3048)
			(end 0.120396 0.3048)
			(stroke
				(width 0.1)
				(type default)
			)
			(layer "F.Fab")
		)
		(fp_line
			(start 0.67945 -0.3048)
			(end 0.67945 0.3048)
			(stroke
				(width 0.1)
				(type default)
			)
			(layer "F.Fab")
		)
		(fp_line
			(start 0.12065 -0.2794)
			(end 0.12065 -0.3048)
			(stroke
				(width 0.1)
				(type default)
			)
			(layer "F.Fab")
		)
		(fp_line
			(start 0.12065 -0.3048)
			(end 0.67945 -0.3048)
			(stroke
				(width 0.1)
				(type default)
			)
			(layer "F.Fab")
		)
		(fp_line
			(start 0.120396 0.3048)
			(end 0.120396 0.2794)
			(stroke
				(width 0.1)
				(type default)
			)
			(layer "F.Fab")
		)
		(fp_line
			(start 0.120396 0.2794)
			(end -0.12065 0.2794)
			(stroke
				(width 0.1)
				(type default)
			)
			(layer "F.Fab")
		)
		(fp_line
			(start -0.12065 0.3048)
			(end -0.67945 0.3048)
			(stroke
				(width 0.1)
				(type default)
			)
			(layer "F.Fab")
		)
		(fp_line
			(start -0.12065 0.2794)
			(end -0.12065 0.3048)
			(stroke
				(width 0.1)
				(type default)
			)
			(layer "F.Fab")
		)
		(fp_line
			(start -0.12065 -0.2794)
			(end 0.12065 -0.2794)
			(stroke
				(width 0.1)
				(type default)
			)
			(layer "F.Fab")
		)
		(fp_line
			(start -0.12065 -0.305054)
			(end -0.12065 -0.2794)
			(stroke
				(width 0.1)
				(type default)
			)
			(layer "F.Fab")
		)
		(fp_line
			(start -0.67945 0.3048)
			(end -0.67945 -0.305054)
			(stroke
				(width 0.1)
				(type default)
			)
			(layer "F.Fab")
		)
		(fp_line
			(start -0.67945 -0.305054)
			(end -0.12065 -0.305054)
			(stroke
				(width 0.1)
				(type default)
			)
			(layer "F.Fab")
		)
		(pad "1" smd circle
			(at -0.40005 0 180)
			(size 0 0)
			(layers "F.Cu" "F.Mask" "F.Paste")
			(net "PVDDCR_SOC_P0")
		)
		(pad "2" smd circle
			(at 0.40005 0 180)
			(size 0 0)
			(layers "F.Cu" "F.Mask" "F.Paste")
			(net "GND")
		)
	)
)
